(kicad_pcb
	(version 20260206)
	(generator "pcbnew")
	(generator_version "10.0")
	(general
		(thickness 1.6)
		(legacy_teardrops no)
	)
	(paper "A4")
	(title_block
		(title "Bryce Canyon_SCC_16316-1_OCP.brd")
		(comment 1 "Bryce Canyon / footprints 1221-1228 of 1561")
	)
	(layers
		(0 "F.Cu" signal "TOP")
		(4 "In1.Cu" signal "L2GND")
		(6 "In2.Cu" signal "L3")
		(8 "In3.Cu" signal "L4VCC")
		(10 "In4.Cu" signal "L5VCC")
		(12 "In5.Cu" signal "L6")
		(14 "In6.Cu" signal "L7GND")
		(2 "B.Cu" signal "BOTTOM")
		(9 "F.Adhes" user "F.Adhesive")
		(11 "B.Adhes" user "B.Adhesive")
		(13 "F.Paste" user "Package Geometry/Pastemask Top")
		(15 "B.Paste" user "Package Geometry/Pastemask Bottom")
		(5 "F.SilkS" user "Ref Des/Silkscreen Top")
		(7 "B.SilkS" user "Ref Des/Silkscreen Bottom")
		(1 "F.Mask" user "Board Geometry/Soldermask Top")
		(3 "B.Mask" user "Board Geometry/Soldermask Bottom")
		(17 "Dwgs.User" user "User.Drawings")
		(19 "Cmts.User" user "User.Comments")
		(21 "Eco1.User" user "User.Eco1")
		(23 "Eco2.User" user "User.Eco2")
		(25 "Edge.Cuts" user "Board Geometry/Outline")
		(27 "Margin" user)
		(31 "F.CrtYd" user "Package Geometry/Place Bound Top")
		(29 "B.CrtYd" user "Package Geometry/Place Bound Bottom")
		(35 "F.Fab" user "Ref Des/Assembly Top")
		(33 "B.Fab" user "Ref Des/Assembly Bottom")
	)
	(footprint ""
		(layer "B.Cu")
		(at 202.820778 -31.646622 90)
		(property "Reference" "L22"
			(at 0 0 90)
			(layer "B.SilkS")
			(hide yes)
			(effects
				(font
					(size 1.27 1.27)
				)
				(justify mirror)
			)
		)
		(property "Value" "MPZ2012S601AT-GP"
			(at 0 -4.2418 90)
			(unlocked yes)
			(layer "B.Fab")
			(hide yes)
			(effects
				(font
					(size 1.016 1.016)
					(thickness 0.1524)
				)
				(justify mirror)
			)
		)
		(property "Device Type" "L805H42"
			(at 0 -5.7912 90)
			(unlocked yes)
			(layer "B.Fab")
			(hide yes)
			(effects
				(font
					(size 1.016 1.016)
					(thickness 0.1524)
				)
				(justify mirror)
			)
		)
		(duplicate_pad_numbers_are_jumpers no)
		(fp_line
			(start 0.889 -1.7018)
			(end -0.889 -1.7018)
			(stroke
				(width 0.1524)
				(type default)
			)
			(layer "B.SilkS")
		)
		(fp_line
			(start -0.889 -1.7018)
			(end -0.889 1.7018)
			(stroke
				(width 0.1524)
				(type default)
			)
			(layer "B.SilkS")
		)
		(fp_line
			(start 0.889 1.7018)
			(end 0.889 -1.7018)
			(stroke
				(width 0.1524)
				(type default)
			)
			(layer "B.SilkS")
		)
		(fp_line
			(start -0.889 1.7018)
			(end 0.889 1.7018)
			(stroke
				(width 0.1524)
				(type default)
			)
			(layer "B.SilkS")
		)
		(fp_rect
			(start 0.9652 1.778)
			(end -0.9652 -1.778)
			(stroke
				(width 0)
				(type default)
			)
			(fill no)
			(layer "B.CrtYd")
		)
		(fp_rect
			(start 0.9652 1.778)
			(end -0.9652 -1.778)
			(stroke
				(width 0)
				(type default)
			)
			(fill no)
			(layer "B.Fab")
		)
		(pad "1" smd rect
			(at 0 -0.9652 270)
			(size 1.397 1.143)
			(layers "B.Cu" "B.Mask" "B.Paste")
			(net "PLL_VDD")
		)
		(pad "2" smd rect
			(at 0 0.9652 270)
			(size 1.397 1.143)
			(layers "B.Cu" "B.Mask" "B.Paste")
			(net "P1V8_C")
		)
	)
	(footprint ""
		(layer "B.Cu")
		(at 131.829048 -119.398034 -90)
		(property "Reference" "C609"
			(at 0 0 90)
			(layer "B.SilkS")
			(hide yes)
			(effects
				(font
					(size 1.27 1.27)
				)
				(justify mirror)
			)
		)
		(property "Value" "SC10U6D3V5KX-4GP"
			(at 0.0762 -6.1214 270)
			(unlocked yes)
			(layer "B.Fab")
			(hide yes)
			(effects
				(font
					(size 1.016 1.016)
					(thickness 0.1524)
				)
				(justify mirror)
			)
		)
		(property "Device Type" "C805H58"
			(at 0.0762 -8.1534 270)
			(unlocked yes)
			(layer "B.Fab")
			(hide yes)
			(effects
				(font
					(size 1.016 1.016)
					(thickness 0.1524)
				)
				(justify mirror)
			)
		)
		(duplicate_pad_numbers_are_jumpers no)
		(fp_line
			(start -0.635 0)
			(end 0.635 0)
			(stroke
				(width 0.508)
				(type default)
			)
			(layer "B.SilkS")
		)
		(fp_rect
			(start 0.9652 1.778)
			(end -0.9652 -1.778)
			(stroke
				(width 0)
				(type default)
			)
			(fill no)
			(layer "B.CrtYd")
		)
		(fp_poly
			(pts
				(xy 0.9652 -1.778) (xy -0.9652 -1.778) (xy -0.9652 1.778) (xy 0.9652 1.778)
			)
			(stroke
				(width 0)
				(type default)
			)
			(fill no)
			(layer "B.Fab")
		)
		(pad "1" smd rect
			(at 0 -0.9652 90)
			(size 1.397 1.143)
			(layers "B.Cu" "B.Mask" "B.Paste")
			(net "P1V5_C")
		)
		(pad "2" smd rect
			(at 0 0.9652 90)
			(size 1.397 1.143)
			(layers "B.Cu" "B.Mask" "B.Paste")
			(net "GND")
		)
	)
	(footprint ""
		(layer "B.Cu")
		(at 186.563 -35.3568 90)
		(property "Reference" "TP98"
			(at 0 0 90)
			(layer "B.SilkS")
			(hide yes)
			(effects
				(font
					(size 1.27 1.27)
				)
				(justify mirror)
			)
		)
		(property "Value" "TPAD28-2-GP"
			(at 0.0127 -1.6637 90)
			(unlocked yes)
			(layer "B.Fab")
			(hide yes)
			(effects
				(font
					(size 1.016 1.016)
					(thickness 0.1524)
				)
				(justify mirror)
			)
		)
		(property "Device Type" "TPAD28"
			(at 0.0127 -3.1877 90)
			(unlocked yes)
			(layer "B.Fab")
			(hide yes)
			(effects
				(font
					(size 1.016 1.016)
					(thickness 0.1524)
				)
				(justify mirror)
			)
		)
		(duplicate_pad_numbers_are_jumpers no)
		(fp_poly
			(pts
				(arc
					(start 0 0.3556)
					(mid 0 -0.3556)
					(end 0 0.3556)
				)
			)
			(stroke
				(width 0)
				(type default)
			)
			(fill no)
			(layer "B.CrtYd")
		)
		(fp_poly
			(pts
				(arc
					(start 0 0.6096)
					(mid 0 -0.6096)
					(end 0 0.6096)
				)
			)
			(stroke
				(width 0)
				(type default)
			)
			(fill no)
			(layer "B.Fab")
		)
		(pad "1" smd circle
			(at 0 0 270)
			(size 0.7112 0.7112)
			(layers "B.Cu" "B.Mask" "B.Paste")
			(net "IOC_GPIO_36")
		)
	)
	(footprint ""
		(layer "B.Cu")
		(at 98.7298 -44.2214 180)
		(property "Reference" "C85"
			(at 0 0 0)
			(layer "B.SilkS")
			(hide yes)
			(effects
				(font
					(size 1.27 1.27)
				)
				(justify mirror)
			)
		)
		(property "Value" "SCD01U16V1KX-GP"
			(at 2.8321 -1.7399 180)
			(unlocked yes)
			(layer "B.Fab")
			(hide yes)
			(effects
				(font
					(size 1.016 1.016)
					(thickness 0.1524)
				)
				(justify mirror)
			)
		)
		(property "Device Type" "C0201H13"
			(at 2.8321 -3.2639 180)
			(unlocked yes)
			(layer "B.Fab")
			(hide yes)
			(effects
				(font
					(size 1.016 1.016)
					(thickness 0.1524)
				)
				(justify mirror)
			)
		)
		(duplicate_pad_numbers_are_jumpers no)
		(fp_rect
			(start 0.2794 0.6477)
			(end -0.2794 -0.6477)
			(stroke
				(width 0)
				(type default)
			)
			(fill no)
			(layer "B.CrtYd")
		)
		(fp_rect
			(start 0.2794 0.6477)
			(end -0.2794 -0.6477)
			(stroke
				(width 0)
				(type default)
			)
			(fill no)
			(layer "B.Fab")
		)
		(pad "1" smd custom
			(at 0 -0.2794)
			(size 0.0762 0.0762)
			(layers "B.Cu" "B.Mask" "B.Paste")
			(net "PHY_DPB_TO_SCC_17_DP")
			(options
				(clearance outline)
				(anchor circle)
			)
			(primitives
				(gr_poly
					(pts
						(arc
							(start 0.1524 0.127)
							(mid 0.137521 0.162921)
							(end 0.1016 0.1778)
						)
						(arc
							(start -0.1016 0.1778)
							(mid -0.137521 0.162921)
							(end -0.1524 0.127)
						)
						(arc
							(start -0.1524 -0.127)
							(mid -0.137521 -0.162921)
							(end -0.1016 -0.1778)
						)
						(arc
							(start 0.1016 -0.1778)
							(mid 0.137521 -0.162921)
							(end 0.1524 -0.127)
						)
					)
					(width 0)
					(fill yes)
				)
			)
		)
		(pad "2" smd custom
			(at 0 0.2794)
			(size 0.0762 0.0762)
			(layers "B.Cu" "B.Mask" "B.Paste")
			(net "PHY_DPB_TO_SCC_C_17_DP")
			(options
				(clearance outline)
				(anchor circle)
			)
			(primitives
				(gr_poly
					(pts
						(arc
							(start 0.1524 0.127)
							(mid 0.137521 0.162921)
							(end 0.1016 0.1778)
						)
						(arc
							(start -0.1016 0.1778)
							(mid -0.137521 0.162921)
							(end -0.1524 0.127)
						)
						(arc
							(start -0.1524 -0.127)
							(mid -0.137521 -0.162921)
							(end -0.1016 -0.1778)
						)
						(arc
							(start 0.1016 -0.1778)
							(mid 0.137521 -0.162921)
							(end 0.1524 -0.127)
						)
					)
					(width 0)
					(fill yes)
				)
			)
		)
	)
	(footprint ""
		(layer "B.Cu")
		(at 124.7267 -70.485 90)
		(property "Reference" "C279"
			(at 0 0 90)
			(layer "B.SilkS")
			(hide yes)
			(effects
				(font
					(size 1.27 1.27)
				)
				(justify mirror)
			)
		)
		(property "Value" "SCD1U6D3V1KX-GP"
			(at 2.8321 -1.7399 90)
			(unlocked yes)
			(layer "B.Fab")
			(hide yes)
			(effects
				(font
					(size 1.016 1.016)
					(thickness 0.1524)
				)
				(justify mirror)
			)
		)
		(property "Device Type" "C0201H13"
			(at 2.8321 -3.2639 90)
			(unlocked yes)
			(layer "B.Fab")
			(hide yes)
			(effects
				(font
					(size 1.016 1.016)
					(thickness 0.1524)
				)
				(justify mirror)
			)
		)
		(duplicate_pad_numbers_are_jumpers no)
		(fp_rect
			(start 0.2794 0.6477)
			(end -0.2794 -0.6477)
			(stroke
				(width 0)
				(type default)
			)
			(fill no)
			(layer "B.CrtYd")
		)
		(fp_rect
			(start 0.2794 0.6477)
			(end -0.2794 -0.6477)
			(stroke
				(width 0)
				(type default)
			)
			(fill no)
			(layer "B.Fab")
		)
		(pad "1" smd custom
			(at 0 -0.2794 270)
			(size 0.0762 0.0762)
			(layers "B.Cu" "B.Mask" "B.Paste")
			(net "GB_VDDA")
			(options
				(clearance outline)
				(anchor circle)
			)
			(primitives
				(gr_poly
					(pts
						(arc
							(start 0.1524 0.127)
							(mid 0.137521 0.162921)
							(end 0.1016 0.1778)
						)
						(arc
							(start -0.1016 0.1778)
							(mid -0.137521 0.162921)
							(end -0.1524 0.127)
						)
						(arc
							(start -0.1524 -0.127)
							(mid -0.137521 -0.162921)
							(end -0.1016 -0.1778)
						)
						(arc
							(start 0.1016 -0.1778)
							(mid 0.137521 -0.162921)
							(end 0.1524 -0.127)
						)
					)
					(width 0)
					(fill yes)
				)
			)
		)
		(pad "2" smd custom
			(at 0 0.2794 270)
			(size 0.0762 0.0762)
			(layers "B.Cu" "B.Mask" "B.Paste")
			(net "GND")
			(options
				(clearance outline)
				(anchor circle)
			)
			(primitives
				(gr_poly
					(pts
						(arc
							(start 0.1524 0.127)
							(mid 0.137521 0.162921)
							(end 0.1016 0.1778)
						)
						(arc
							(start -0.1016 0.1778)
							(mid -0.137521 0.162921)
							(end -0.1524 0.127)
						)
						(arc
							(start -0.1524 -0.127)
							(mid -0.137521 -0.162921)
							(end -0.1016 -0.1778)
						)
						(arc
							(start 0.1016 -0.1778)
							(mid 0.137521 -0.162921)
							(end 0.1524 -0.127)
						)
					)
					(width 0)
					(fill yes)
				)
			)
		)
	)
	(footprint ""
		(layer "B.Cu")
		(at 163.449 -42.164 -90)
		(property "Reference" "R178"
			(at 0 0 90)
			(layer "B.SilkS")
			(hide yes)
			(effects
				(font
					(size 1.27 1.27)
				)
				(justify mirror)
			)
		)
		(property "Value" "10KR2F-2-GP"
			(at -0.064008 -3.993896 270)
			(unlocked yes)
			(layer "B.Fab")
			(hide yes)
			(effects
				(font
					(size 1.016 1.016)
					(thickness 0.1524)
				)
				(justify mirror)
			)
		)
		(property "Device Type" "R402H16"
			(at -0.064008 -5.517896 270)
			(unlocked yes)
			(layer "B.Fab")
			(hide yes)
			(effects
				(font
					(size 1.016 1.016)
					(thickness 0.1524)
				)
				(justify mirror)
			)
		)
		(duplicate_pad_numbers_are_jumpers no)
		(fp_line
			(start -0.508 -0.9398)
			(end 0.508 -0.9398)
			(stroke
				(width 0.1524)
				(type default)
			)
			(layer "B.SilkS")
		)
		(fp_line
			(start 0.508 -0.9398)
			(end 0.508 0.9398)
			(stroke
				(width 0.1524)
				(type default)
			)
			(layer "B.SilkS")
		)
		(fp_rect
			(start 0.508 0.9398)
			(end -0.508 -0.9398)
			(stroke
				(width 0)
				(type default)
			)
			(fill no)
			(layer "B.CrtYd")
		)
		(fp_rect
			(start 0.508 0.9398)
			(end -0.508 -0.9398)
			(stroke
				(width 0)
				(type default)
			)
			(fill no)
			(layer "B.Fab")
		)
		(pad "1" smd custom
			(at 0 -0.4445 90)
			(size 0.1397 0.1397)
			(layers "B.Cu" "B.Mask" "B.Paste")
			(net "IOC_SIO_BLINK")
			(options
				(clearance outline)
				(anchor circle)
			)
			(primitives
				(gr_poly
					(pts
						(arc
							(start -0.1778 0.2794)
							(mid -0.249642 0.249642)
							(end -0.2794 0.1778)
						)
						(arc
							(start -0.2794 -0.1778)
							(mid -0.249642 -0.249642)
							(end -0.1778 -0.2794)
						)
						(arc
							(start 0.1778 -0.2794)
							(mid 0.249642 -0.249642)
							(end 0.2794 -0.1778)
						)
						(arc
							(start 0.2794 0.1778)
							(mid 0.249642 0.249642)
							(end 0.1778 0.2794)
						)
					)
					(width 0)
					(fill yes)
				)
			)
		)
		(pad "2" smd custom
			(at 0 0.4445 90)
			(size 0.1397 0.1397)
			(layers "B.Cu" "B.Mask" "B.Paste")
			(net "GND")
			(options
				(clearance outline)
				(anchor circle)
			)
			(primitives
				(gr_poly
					(pts
						(arc
							(start -0.1778 0.2794)
							(mid -0.249642 0.249642)
							(end -0.2794 0.1778)
						)
						(arc
							(start -0.2794 -0.1778)
							(mid -0.249642 -0.249642)
							(end -0.1778 -0.2794)
						)
						(arc
							(start 0.1778 -0.2794)
							(mid 0.249642 -0.249642)
							(end 0.2794 -0.1778)
						)
						(arc
							(start 0.2794 0.1778)
							(mid 0.249642 0.249642)
							(end 0.1778 0.2794)
						)
					)
					(width 0)
					(fill yes)
				)
			)
		)
	)
	(footprint ""
		(layer "B.Cu")
		(at 99.5426 -86.9696)
		(property "Reference" "R79"
			(at 0 0 0)
			(layer "B.SilkS")
			(hide yes)
			(effects
				(font
					(size 1.27 1.27)
				)
				(justify mirror)
			)
		)
		(property "Value" "4K7R2F-GP"
			(at -0.064008 -3.993896 0)
			(unlocked yes)
			(layer "B.Fab")
			(hide yes)
			(effects
				(font
					(size 1.016 1.016)
					(thickness 0.1524)
				)
				(justify mirror)
			)
		)
		(property "Device Type" "R402H16"
			(at -0.064008 -5.517896 0)
			(unlocked yes)
			(layer "B.Fab")
			(hide yes)
			(effects
				(font
					(size 1.016 1.016)
					(thickness 0.1524)
				)
				(justify mirror)
			)
		)
		(duplicate_pad_numbers_are_jumpers no)
		(fp_line
			(start -0.508 -0.9398)
			(end 0.508 -0.9398)
			(stroke
				(width 0.1524)
				(type default)
			)
			(layer "B.SilkS")
		)
		(fp_line
			(start 0.508 -0.9398)
			(end 0.508 0.9398)
			(stroke
				(width 0.1524)
				(type default)
			)
			(layer "B.SilkS")
		)
		(fp_rect
			(start 0.508 0.9398)
			(end -0.508 -0.9398)
			(stroke
				(width 0)
				(type default)
			)
			(fill no)
			(layer "B.CrtYd")
		)
		(fp_rect
			(start 0.508 0.9398)
			(end -0.508 -0.9398)
			(stroke
				(width 0)
				(type default)
			)
			(fill no)
			(layer "B.Fab")
		)
		(pad "1" smd custom
			(at 0 -0.4445 180)
			(size 0.1397 0.1397)
			(layers "B.Cu" "B.Mask" "B.Paste")
			(net "SCC_TYPE_0_LS")
			(options
				(clearance outline)
				(anchor circle)
			)
			(primitives
				(gr_poly
					(pts
						(arc
							(start -0.1778 0.2794)
							(mid -0.249642 0.249642)
							(end -0.2794 0.1778)
						)
						(arc
							(start -0.2794 -0.1778)
							(mid -0.249642 -0.249642)
							(end -0.1778 -0.2794)
						)
						(arc
							(start 0.1778 -0.2794)
							(mid 0.249642 -0.249642)
							(end 0.2794 -0.1778)
						)
						(arc
							(start 0.2794 0.1778)
							(mid 0.249642 0.249642)
							(end 0.1778 0.2794)
						)
					)
					(width 0)
					(fill yes)
				)
			)
		)
		(pad "2" smd custom
			(at 0 0.4445 180)
			(size 0.1397 0.1397)
			(layers "B.Cu" "B.Mask" "B.Paste")
			(net "GND")
			(options
				(clearance outline)
				(anchor circle)
			)
			(primitives
				(gr_poly
					(pts
						(arc
							(start -0.1778 0.2794)
							(mid -0.249642 0.249642)
							(end -0.2794 0.1778)
						)
						(arc
							(start -0.2794 -0.1778)
							(mid -0.249642 -0.249642)
							(end -0.1778 -0.2794)
						)
						(arc
							(start 0.1778 -0.2794)
							(mid 0.249642 -0.249642)
							(end 0.2794 -0.1778)
						)
						(arc
							(start 0.2794 0.1778)
							(mid 0.249642 0.249642)
							(end 0.1778 0.2794)
						)
					)
					(width 0)
					(fill yes)
				)
			)
		)
	)
	(footprint ""
		(layer "B.Cu")
		(at 178.1302 -31.75 -90)
		(property "Reference" "C471"
			(at 0 0 90)
			(layer "B.SilkS")
			(hide yes)
			(effects
				(font
					(size 1.27 1.27)
				)
				(justify mirror)
			)
		)
		(property "Value" "SCD1U6D3V1KX-GP"
			(at 2.8321 -1.7399 270)
			(unlocked yes)
			(layer "B.Fab")
			(hide yes)
			(effects
				(font
					(size 1.016 1.016)
					(thickness 0.1524)
				)
				(justify mirror)
			)
		)
		(property "Device Type" "C0201H13"
			(at 2.8321 -3.2639 270)
			(unlocked yes)
			(layer "B.Fab")
			(hide yes)
			(effects
				(font
					(size 1.016 1.016)
					(thickness 0.1524)
				)
				(justify mirror)
			)
		)
		(duplicate_pad_numbers_are_jumpers no)
		(fp_rect
			(start 0.2794 0.6477)
			(end -0.2794 -0.6477)
			(stroke
				(width 0)
				(type default)
			)
			(fill no)
			(layer "B.CrtYd")
		)
		(fp_rect
			(start 0.2794 0.6477)
			(end -0.2794 -0.6477)
			(stroke
				(width 0)
				(type default)
			)
			(fill no)
			(layer "B.Fab")
		)
		(pad "1" smd custom
			(at 0 -0.2794 90)
			(size 0.0762 0.0762)
			(layers "B.Cu" "B.Mask" "B.Paste")
			(net "P1V8_C")
			(options
				(clearance outline)
				(anchor circle)
			)
			(primitives
				(gr_poly
					(pts
						(arc
							(start 0.1524 0.127)
							(mid 0.137521 0.162921)
							(end 0.1016 0.1778)
						)
						(arc
							(start -0.1016 0.1778)
							(mid -0.137521 0.162921)
							(end -0.1524 0.127)
						)
						(arc
							(start -0.1524 -0.127)
							(mid -0.137521 -0.162921)
							(end -0.1016 -0.1778)
						)
						(arc
							(start 0.1016 -0.1778)
							(mid 0.137521 -0.162921)
							(end 0.1524 -0.127)
						)
					)
					(width 0)
					(fill yes)
				)
			)
		)
		(pad "2" smd custom
			(at 0 0.2794 90)
			(size 0.0762 0.0762)
			(layers "B.Cu" "B.Mask" "B.Paste")
			(net "GND")
			(options
				(clearance outline)
				(anchor circle)
			)
			(primitives
				(gr_poly
					(pts
						(arc
							(start 0.1524 0.127)
							(mid 0.137521 0.162921)
							(end 0.1016 0.1778)
						)
						(arc
							(start -0.1016 0.1778)
							(mid -0.137521 0.162921)
							(end -0.1524 0.127)
						)
						(arc
							(start -0.1524 -0.127)
							(mid -0.137521 -0.162921)
							(end -0.1016 -0.1778)
						)
						(arc
							(start 0.1016 -0.1778)
							(mid 0.137521 -0.162921)
							(end 0.1524 -0.127)
						)
					)
					(width 0)
					(fill yes)
				)
			)
		)
	)
)
